# S9S_MB_2U (Grand Teton) — schematic netlist excerpt (pin names and nets, part order shuffled) for the footprints in the layout excerpt that follows; sources: Cadence DE-HDL packaged netlist, KiCad conversion of 03242023_DA0F0TMBIJ0_F0T_Motherboard_J_brd_V01_OCP.brd

R2733  Q_RES  33.2 1% CHIP  pkg 0402LF  page 114 : A = PWRGD_CHF_CPU0_DIMM2 ; B = PWRGD_FAIL_CPU0_EF
C1184  Q_CAP  22UF 6.3V 20% X6S  pkg C0603  page 189 : A = P3V3_AUX ; B = GND

(kicad_pcb
	(version 20260206)
	(generator "pcbnew")
	(generator_version "10.0")
	(general
		(thickness 1.6)
		(legacy_teardrops no)
	)
	(paper "A4")
	(title_block
		(title "03242023_DA0F0TMBIJ0_F0T_Motherboard_J_brd_V01_OCP.brd")
		(comment 1 "Grand Teton / footprints 5610-5611 of 6105")
	)
	(layers
		(0 "F.Cu" signal "TOP")
		(4 "In1.Cu" signal "GND")
		(6 "In2.Cu" signal "IN1")
		(8 "In3.Cu" signal "GND1")
		(10 "In4.Cu" signal "IN2")
		(12 "In5.Cu" signal "GND2")
		(14 "In6.Cu" signal "IN3")
		(16 "In7.Cu" signal "GND3")
		(18 "In8.Cu" signal "VCC")
		(20 "In9.Cu" signal "VCC1")
		(22 "In10.Cu" signal "GND4")
		(24 "In11.Cu" signal "IN4")
		(26 "In12.Cu" signal "GND5")
		(28 "In13.Cu" signal "IN5")
		(30 "In14.Cu" signal "GND6")
		(32 "In15.Cu" signal "IN6")
		(34 "In16.Cu" signal "GND7")
		(2 "B.Cu" signal "BOTTOM")
		(9 "F.Adhes" user "F.Adhesive")
		(11 "B.Adhes" user "B.Adhesive")
		(13 "F.Paste" user "Package Geometry/Pastemask Top")
		(15 "B.Paste" user "Package Geometry/Pastemask Bottom")
		(5 "F.SilkS" user "Ref Des/Silkscreen Top")
		(7 "B.SilkS" user "Ref Des/Silkscreen Bottom")
		(1 "F.Mask" user "Board Geometry/Soldermask Top")
		(3 "B.Mask" user "Board Geometry/Soldermask Bottom")
		(17 "Dwgs.User" user "User.Drawings")
		(19 "Cmts.User" user "User.Comments")
		(21 "Eco1.User" user "User.Eco1")
		(23 "Eco2.User" user "User.Eco2")
		(25 "Edge.Cuts" user "Board Geometry/Outline")
		(27 "Margin" user)
		(31 "F.CrtYd" user "Package Geometry/Place Bound Top")
		(29 "B.CrtYd" user "Package Geometry/Place Bound Bottom")
		(35 "F.Fab" user "Ref Des/Assembly Top")
		(33 "B.Fab" user "Ref Des/Assembly Bottom")
	)
	(footprint ""
		(layer "B.Cu")
		(at 318.262254 -65.048892)
		(property "Reference" "C1184"
			(at 0 0 0)
			(layer "B.SilkS")
			(hide yes)
			(effects
				(font
					(size 1.27 1.27)
				)
				(justify mirror)
			)
		)
		(property "Value" ""
			(at 0 0 0)
			(layer "B.Fab")
			(effects
				(font
					(size 1.27 1.27)
				)
				(justify mirror)
			)
		)
		(duplicate_pad_numbers_are_jumpers no)
		(fp_line
			(start -1.2954 -0.5842)
			(end -1.2954 0.5842)
			(stroke
				(width 0.1524)
				(type default)
			)
			(layer "B.SilkS")
		)
		(fp_line
			(start -1.2954 0.5842)
			(end 1.2954 0.5842)
			(stroke
				(width 0.1524)
				(type default)
			)
			(layer "B.SilkS")
		)
		(fp_line
			(start 0 -0.5842)
			(end 0 0.5842)
			(stroke
				(width 0.1524)
				(type default)
			)
			(layer "B.SilkS")
		)
		(fp_line
			(start 1.2954 -0.5842)
			(end -1.2954 -0.5842)
			(stroke
				(width 0.1524)
				(type default)
			)
			(layer "B.SilkS")
		)
		(fp_line
			(start 1.2954 0.5842)
			(end 1.2954 -0.5842)
			(stroke
				(width 0.1524)
				(type default)
			)
			(layer "B.SilkS")
		)
		(fp_line
			(start -1.1938 -0.4064)
			(end -1.1938 0.4064)
			(stroke
				(width 0.1)
				(type default)
			)
			(layer "B.Fab")
		)
		(fp_line
			(start -1.1938 0.4064)
			(end -0.8636 0.4064)
			(stroke
				(width 0.1)
				(type default)
			)
			(layer "B.Fab")
		)
		(fp_line
			(start -0.8636 -0.4572)
			(end -0.8636 -0.4064)
			(stroke
				(width 0.1)
				(type default)
			)
			(layer "B.Fab")
		)
		(fp_line
			(start -0.8636 -0.4064)
			(end -1.1938 -0.4064)
			(stroke
				(width 0.1)
				(type default)
			)
			(layer "B.Fab")
		)
		(fp_line
			(start -0.8636 0.4064)
			(end -0.8636 0.4572)
			(stroke
				(width 0.1)
				(type default)
			)
			(layer "B.Fab")
		)
		(fp_line
			(start -0.8636 0.4572)
			(end 0.8636 0.4572)
			(stroke
				(width 0.1)
				(type default)
			)
			(layer "B.Fab")
		)
		(fp_line
			(start 0.8636 -0.4572)
			(end -0.8636 -0.4572)
			(stroke
				(width 0.1)
				(type default)
			)
			(layer "B.Fab")
		)
		(fp_line
			(start 0.8636 -0.4064)
			(end 0.8636 -0.4572)
			(stroke
				(width 0.1)
				(type default)
			)
			(layer "B.Fab")
		)
		(fp_line
			(start 0.8636 0.4064)
			(end 1.1938 0.4064)
			(stroke
				(width 0.1)
				(type default)
			)
			(layer "B.Fab")
		)
		(fp_line
			(start 0.8636 0.4572)
			(end 0.8636 0.4064)
			(stroke
				(width 0.1)
				(type default)
			)
			(layer "B.Fab")
		)
		(fp_line
			(start 1.1938 -0.4064)
			(end 0.8636 -0.4064)
			(stroke
				(width 0.1)
				(type default)
			)
			(layer "B.Fab")
		)
		(fp_line
			(start 1.1938 0.4064)
			(end 1.1938 -0.4064)
			(stroke
				(width 0.1)
				(type default)
			)
			(layer "B.Fab")
		)
		(pad "1" smd rect
			(at 0.7366 0 270)
			(size 0.7112 0.8128)
			(layers "B.Cu" "B.Mask" "B.Paste")
			(net "P3V3_AUX")
		)
		(pad "2" smd rect
			(at -0.7366 0 270)
			(size 0.7112 0.8128)
			(layers "B.Cu" "B.Mask" "B.Paste")
			(net "GND")
		)
	)
	(footprint ""
		(layer "B.Cu")
		(at 425.555156 -318.908176 90)
		(property "Reference" "R2733"
			(at 0 0 90)
			(layer "B.SilkS")
			(hide yes)
			(effects
				(font
					(size 1.27 1.27)
				)
				(justify mirror)
			)
		)
		(property "Value" ""
			(at 0 0 90)
			(layer "B.Fab")
			(effects
				(font
					(size 1.27 1.27)
				)
				(justify mirror)
			)
		)
		(duplicate_pad_numbers_are_jumpers no)
		(fp_line
			(start 0.7874 -0.4064)
			(end -0.7874 -0.4064)
			(stroke
				(width 0.1524)
				(type default)
			)
			(layer "B.SilkS")
		)
		(fp_line
			(start -0.7874 -0.4064)
			(end -0.7874 0.4064)
			(stroke
				(width 0.1524)
				(type default)
			)
			(layer "B.SilkS")
		)
		(fp_line
			(start 0.7874 0.4064)
			(end 0.7874 -0.4064)
			(stroke
				(width 0.1524)
				(type default)
			)
			(layer "B.SilkS")
		)
		(fp_line
			(start -0.7874 0.4064)
			(end 0.7874 0.4064)
			(stroke
				(width 0.1524)
				(type default)
			)
			(layer "B.SilkS")
		)
		(fp_line
			(start 0.67945 -0.305054)
			(end 0.12065 -0.305054)
			(stroke
				(width 0.1)
				(type default)
			)
			(layer "B.Fab")
		)
		(fp_line
			(start 0.12065 -0.305054)
			(end 0.12065 -0.2794)
			(stroke
				(width 0.1)
				(type default)
			)
			(layer "B.Fab")
		)
		(fp_line
			(start -0.12065 -0.3048)
			(end -0.67945 -0.3048)
			(stroke
				(width 0.1)
				(type default)
			)
			(layer "B.Fab")
		)
		(fp_line
			(start -0.67945 -0.3048)
			(end -0.67945 0.3048)
			(stroke
				(width 0.1)
				(type default)
			)
			(layer "B.Fab")
		)
		(fp_line
			(start 0.12065 -0.2794)
			(end -0.12065 -0.2794)
			(stroke
				(width 0.1)
				(type default)
			)
			(layer "B.Fab")
		)
		(fp_line
			(start -0.12065 -0.2794)
			(end -0.12065 -0.3048)
			(stroke
				(width 0.1)
				(type default)
			)
			(layer "B.Fab")
		)
		(fp_line
			(start 0.12065 0.2794)
			(end 0.12065 0.3048)
			(stroke
				(width 0.1)
				(type default)
			)
			(layer "B.Fab")
		)
		(fp_line
			(start -0.120396 0.2794)
			(end 0.12065 0.2794)
			(stroke
				(width 0.1)
				(type default)
			)
			(layer "B.Fab")
		)
		(fp_line
			(start 0.67945 0.3048)
			(end 0.67945 -0.305054)
			(stroke
				(width 0.1)
				(type default)
			)
			(layer "B.Fab")
		)
		(fp_line
			(start 0.12065 0.3048)
			(end 0.67945 0.3048)
			(stroke
				(width 0.1)
				(type default)
			)
			(layer "B.Fab")
		)
		(fp_line
			(start -0.120396 0.3048)
			(end -0.120396 0.2794)
			(stroke
				(width 0.1)
				(type default)
			)
			(layer "B.Fab")
		)
		(fp_line
			(start -0.67945 0.3048)
			(end -0.120396 0.3048)
			(stroke
				(width 0.1)
				(type default)
			)
			(layer "B.Fab")
		)
		(pad "1" smd circle
			(at 0.40005 0 270)
			(size 0 0)
			(layers "B.Cu" "B.Mask" "B.Paste")
			(net "PWRGD_CHF_CPU0_DIMM2")
		)
		(pad "2" smd circle
			(at -0.40005 0 270)
			(size 0 0)
			(layers "B.Cu" "B.Mask" "B.Paste")
			(net "PWRGD_FAIL_CPU0_EF")
		)
	)
)
